# S9S_MB_2U (Grand Teton) — schematic netlist excerpt (pin names and nets, part order shuffled) for the footprints in the layout excerpt that follows; sources: Cadence DE-HDL packaged netlist, KiCad conversion of 03242023_DA0F0TMBIJ0_F0T_Motherboard_J_brd_V01_OCP.brd

R7  Q_RES  33.2 1% CHIP  pkg 0402LF  page 14 : A = H_CPU0_PMDOWN_PCH_R ; B = H_CPU0_PMDOWN_PCH
R768  Q_RES  1K 1% CHIP  pkg 0402LF  page 131 : A = P3V3_AUX ; B = JTAG_DBP_PRESENT_R_N

(kicad_pcb
	(version 20260206)
	(generator "pcbnew")
	(generator_version "10.0")
	(general
		(thickness 1.6)
		(legacy_teardrops no)
	)
	(paper "A4")
	(title_block
		(title "03242023_DA0F0TMBIJ0_F0T_Motherboard_J_brd_V01_OCP.brd")
		(comment 1 "Grand Teton / footprints 687-688 of 6105")
	)
	(layers
		(0 "F.Cu" signal "TOP")
		(4 "In1.Cu" signal "GND")
		(6 "In2.Cu" signal "IN1")
		(8 "In3.Cu" signal "GND1")
		(10 "In4.Cu" signal "IN2")
		(12 "In5.Cu" signal "GND2")
		(14 "In6.Cu" signal "IN3")
		(16 "In7.Cu" signal "GND3")
		(18 "In8.Cu" signal "VCC")
		(20 "In9.Cu" signal "VCC1")
		(22 "In10.Cu" signal "GND4")
		(24 "In11.Cu" signal "IN4")
		(26 "In12.Cu" signal "GND5")
		(28 "In13.Cu" signal "IN5")
		(30 "In14.Cu" signal "GND6")
		(32 "In15.Cu" signal "IN6")
		(34 "In16.Cu" signal "GND7")
		(2 "B.Cu" signal "BOTTOM")
		(9 "F.Adhes" user "F.Adhesive")
		(11 "B.Adhes" user "B.Adhesive")
		(13 "F.Paste" user "Package Geometry/Pastemask Top")
		(15 "B.Paste" user "Package Geometry/Pastemask Bottom")
		(5 "F.SilkS" user "Ref Des/Silkscreen Top")
		(7 "B.SilkS" user "Ref Des/Silkscreen Bottom")
		(1 "F.Mask" user "Board Geometry/Soldermask Top")
		(3 "B.Mask" user "Board Geometry/Soldermask Bottom")
		(17 "Dwgs.User" user "User.Drawings")
		(19 "Cmts.User" user "User.Comments")
		(21 "Eco1.User" user "User.Eco1")
		(23 "Eco2.User" user "User.Eco2")
		(25 "Edge.Cuts" user "Board Geometry/Outline")
		(27 "Margin" user)
		(31 "F.CrtYd" user "Package Geometry/Place Bound Top")
		(29 "B.CrtYd" user "Package Geometry/Place Bound Bottom")
		(35 "F.Fab" user "Ref Des/Assembly Top")
		(33 "B.Fab" user "Ref Des/Assembly Bottom")
	)
	(footprint ""
		(layer "F.Cu")
		(at 385.716272 -59.719464)
		(property "Reference" "R768"
			(at 0 0 0)
			(layer "F.SilkS")
			(hide yes)
			(effects
				(font
					(size 1.27 1.27)
				)
			)
		)
		(property "Value" ""
			(at 0 0 0)
			(layer "F.Fab")
			(effects
				(font
					(size 1.27 1.27)
				)
			)
		)
		(duplicate_pad_numbers_are_jumpers no)
		(fp_line
			(start -0.7874 -0.4064)
			(end 0.7874 -0.4064)
			(stroke
				(width 0.1524)
				(type default)
			)
			(layer "F.SilkS")
		)
		(fp_line
			(start -0.7874 0.4064)
			(end -0.7874 -0.4064)
			(stroke
				(width 0.1524)
				(type default)
			)
			(layer "F.SilkS")
		)
		(fp_line
			(start 0.7874 -0.4064)
			(end 0.7874 0.4064)
			(stroke
				(width 0.1524)
				(type default)
			)
			(layer "F.SilkS")
		)
		(fp_line
			(start 0.7874 0.4064)
			(end -0.7874 0.4064)
			(stroke
				(width 0.1524)
				(type default)
			)
			(layer "F.SilkS")
		)
		(fp_line
			(start -0.67945 -0.305054)
			(end -0.12065 -0.305054)
			(stroke
				(width 0.1)
				(type default)
			)
			(layer "F.Fab")
		)
		(fp_line
			(start -0.67945 0.3048)
			(end -0.67945 -0.305054)
			(stroke
				(width 0.1)
				(type default)
			)
			(layer "F.Fab")
		)
		(fp_line
			(start -0.12065 -0.305054)
			(end -0.12065 -0.2794)
			(stroke
				(width 0.1)
				(type default)
			)
			(layer "F.Fab")
		)
		(fp_line
			(start -0.12065 -0.2794)
			(end 0.12065 -0.2794)
			(stroke
				(width 0.1)
				(type default)
			)
			(layer "F.Fab")
		)
		(fp_line
			(start -0.12065 0.2794)
			(end -0.12065 0.3048)
			(stroke
				(width 0.1)
				(type default)
			)
			(layer "F.Fab")
		)
		(fp_line
			(start -0.12065 0.3048)
			(end -0.67945 0.3048)
			(stroke
				(width 0.1)
				(type default)
			)
			(layer "F.Fab")
		)
		(fp_line
			(start 0.120396 0.2794)
			(end -0.12065 0.2794)
			(stroke
				(width 0.1)
				(type default)
			)
			(layer "F.Fab")
		)
		(fp_line
			(start 0.120396 0.3048)
			(end 0.120396 0.2794)
			(stroke
				(width 0.1)
				(type default)
			)
			(layer "F.Fab")
		)
		(fp_line
			(start 0.12065 -0.3048)
			(end 0.67945 -0.3048)
			(stroke
				(width 0.1)
				(type default)
			)
			(layer "F.Fab")
		)
		(fp_line
			(start 0.12065 -0.2794)
			(end 0.12065 -0.3048)
			(stroke
				(width 0.1)
				(type default)
			)
			(layer "F.Fab")
		)
		(fp_line
			(start 0.67945 -0.3048)
			(end 0.67945 0.3048)
			(stroke
				(width 0.1)
				(type default)
			)
			(layer "F.Fab")
		)
		(fp_line
			(start 0.67945 0.3048)
			(end 0.120396 0.3048)
			(stroke
				(width 0.1)
				(type default)
			)
			(layer "F.Fab")
		)
		(pad "1" smd circle
			(at -0.40005 0)
			(size 0 0)
			(layers "F.Cu" "F.Mask" "F.Paste")
			(net "P3V3_AUX")
		)
		(pad "2" smd circle
			(at 0.40005 0)
			(size 0 0)
			(layers "F.Cu" "F.Mask" "F.Paste")
			(net "JTAG_DBP_PRESENT_R_N")
		)
	)
	(footprint ""
		(layer "F.Cu")
		(at 307.14188 -48.097948)
		(property "Reference" "R7"
			(at 0 0 0)
			(layer "F.SilkS")
			(hide yes)
			(effects
				(font
					(size 1.27 1.27)
				)
			)
		)
		(property "Value" ""
			(at 0 0 0)
			(layer "F.Fab")
			(effects
				(font
					(size 1.27 1.27)
				)
			)
		)
		(duplicate_pad_numbers_are_jumpers no)
		(fp_line
			(start -0.7874 -0.4064)
			(end 0.7874 -0.4064)
			(stroke
				(width 0.1524)
				(type default)
			)
			(layer "F.SilkS")
		)
		(fp_line
			(start -0.7874 0.4064)
			(end -0.7874 -0.4064)
			(stroke
				(width 0.1524)
				(type default)
			)
			(layer "F.SilkS")
		)
		(fp_line
			(start 0.7874 -0.4064)
			(end 0.7874 0.4064)
			(stroke
				(width 0.1524)
				(type default)
			)
			(layer "F.SilkS")
		)
		(fp_line
			(start 0.7874 0.4064)
			(end -0.7874 0.4064)
			(stroke
				(width 0.1524)
				(type default)
			)
			(layer "F.SilkS")
		)
		(fp_line
			(start -0.67945 -0.305054)
			(end -0.12065 -0.305054)
			(stroke
				(width 0.1)
				(type default)
			)
			(layer "F.Fab")
		)
		(fp_line
			(start -0.67945 0.3048)
			(end -0.67945 -0.305054)
			(stroke
				(width 0.1)
				(type default)
			)
			(layer "F.Fab")
		)
		(fp_line
			(start -0.12065 -0.305054)
			(end -0.12065 -0.2794)
			(stroke
				(width 0.1)
				(type default)
			)
			(layer "F.Fab")
		)
		(fp_line
			(start -0.12065 -0.2794)
			(end 0.12065 -0.2794)
			(stroke
				(width 0.1)
				(type default)
			)
			(layer "F.Fab")
		)
		(fp_line
			(start -0.12065 0.2794)
			(end -0.12065 0.3048)
			(stroke
				(width 0.1)
				(type default)
			)
			(layer "F.Fab")
		)
		(fp_line
			(start -0.12065 0.3048)
			(end -0.67945 0.3048)
			(stroke
				(width 0.1)
				(type default)
			)
			(layer "F.Fab")
		)
		(fp_line
			(start 0.120396 0.2794)
			(end -0.12065 0.2794)
			(stroke
				(width 0.1)
				(type default)
			)
			(layer "F.Fab")
		)
		(fp_line
			(start 0.120396 0.3048)
			(end 0.120396 0.2794)
			(stroke
				(width 0.1)
				(type default)
			)
			(layer "F.Fab")
		)
		(fp_line
			(start 0.12065 -0.3048)
			(end 0.67945 -0.3048)
			(stroke
				(width 0.1)
				(type default)
			)
			(layer "F.Fab")
		)
		(fp_line
			(start 0.12065 -0.2794)
			(end 0.12065 -0.3048)
			(stroke
				(width 0.1)
				(type default)
			)
			(layer "F.Fab")
		)
		(fp_line
			(start 0.67945 -0.3048)
			(end 0.67945 0.3048)
			(stroke
				(width 0.1)
				(type default)
			)
			(layer "F.Fab")
		)
		(fp_line
			(start 0.67945 0.3048)
			(end 0.120396 0.3048)
			(stroke
				(width 0.1)
				(type default)
			)
			(layer "F.Fab")
		)
		(pad "1" smd circle
			(at -0.40005 0)
			(size 0 0)
			(layers "F.Cu" "F.Mask" "F.Paste")
			(net "H_CPU0_PMDOWN_PCH_R")
		)
		(pad "2" smd circle
			(at 0.40005 0)
			(size 0 0)
			(layers "F.Cu" "F.Mask" "F.Paste")
			(net "H_CPU0_PMDOWN_PCH")
		)
	)
)
